(kicad_pcb
	(version 20260206)
	(generator "pcbnew")
	(generator_version "10.0")
	(general
		(thickness 1.6)
		(legacy_teardrops no)
	)
	(paper "A4")
	(title_block
		(title "peb — Lightning_PEB_BRD.brd")
		(comment 1 "Lightning (Wiwynn / Facebook NVMe JBOF) / footprints 1685-1692 of 2563")
	)
	(layers
		(0 "F.Cu" signal "TOP")
		(4 "In1.Cu" signal "L2GND")
		(6 "In2.Cu" signal "L3")
		(8 "In3.Cu" signal "L4VCC")
		(10 "In4.Cu" signal "L5VCC")
		(12 "In5.Cu" signal "L6")
		(14 "In6.Cu" signal "L7GND")
		(2 "B.Cu" signal "BOTTOM")
		(9 "F.Adhes" user "F.Adhesive")
		(11 "B.Adhes" user "B.Adhesive")
		(13 "F.Paste" user "Package Geometry/Pastemask Top")
		(15 "B.Paste" user "Package Geometry/Pastemask Bottom")
		(5 "F.SilkS" user "Ref Des/Silkscreen Top")
		(7 "B.SilkS" user "Ref Des/Silkscreen Bottom")
		(1 "F.Mask" user "Board Geometry/Soldermask Top")
		(3 "B.Mask" user "Board Geometry/Soldermask Bottom")
		(17 "Dwgs.User" user "User.Drawings")
		(19 "Cmts.User" user "User.Comments")
		(21 "Eco1.User" user "User.Eco1")
		(23 "Eco2.User" user "User.Eco2")
		(25 "Edge.Cuts" user "Board Geometry/Outline")
		(27 "Margin" user)
		(31 "F.CrtYd" user "Package Geometry/Place Bound Top")
		(29 "B.CrtYd" user "Package Geometry/Place Bound Bottom")
		(35 "F.Fab" user "Ref Des/Assembly Top")
		(33 "B.Fab" user "Ref Des/Assembly Bottom")
	)
	(footprint ""
		(layer "B.Cu")
		(at 158.766002 -64.670432 -90)
		(property "Reference" "PR166"
			(at 0 0 90)
			(layer "B.SilkS")
			(hide yes)
			(effects
				(font
					(size 1.27 1.27)
				)
				(justify mirror)
			)
		)
		(property "Value" "3D01R5F-GP"
			(at 0 -8.9535 270)
			(unlocked yes)
			(layer "B.Fab")
			(hide yes)
			(effects
				(font
					(size 1.27 1.016)
					(thickness 0.1524)
				)
				(justify mirror)
			)
		)
		(property "Device Type" "R805H24"
			(at 0 -10.6299 270)
			(unlocked yes)
			(layer "B.Fab")
			(hide yes)
			(effects
				(font
					(size 1.27 1.016)
					(thickness 0.1524)
				)
				(justify mirror)
			)
		)
		(duplicate_pad_numbers_are_jumpers no)
		(fp_line
			(start -0.889 1.7018)
			(end -0.889 -0.508)
			(stroke
				(width 0.1524)
				(type default)
			)
			(layer "B.SilkS")
		)
		(fp_line
			(start 0.889 1.7018)
			(end -0.889 1.7018)
			(stroke
				(width 0.1524)
				(type default)
			)
			(layer "B.SilkS")
		)
		(fp_line
			(start 0.889 0.0762)
			(end 0.889 1.7018)
			(stroke
				(width 0.1524)
				(type default)
			)
			(layer "B.SilkS")
		)
		(fp_line
			(start -0.889 -1.7018)
			(end -0.889 -0.381)
			(stroke
				(width 0.1524)
				(type default)
			)
			(layer "B.SilkS")
		)
		(fp_line
			(start -0.889 -1.7018)
			(end 0.889 -1.7018)
			(stroke
				(width 0.1524)
				(type default)
			)
			(layer "B.SilkS")
		)
		(fp_line
			(start 0.889 -1.7018)
			(end 0.889 0.2794)
			(stroke
				(width 0.1524)
				(type default)
			)
			(layer "B.SilkS")
		)
		(fp_poly
			(pts
				(xy -0.9652 -1.778) (xy -0.9652 1.778) (xy 0.9652 1.778) (xy 0.9652 -1.778)
			)
			(stroke
				(width 0)
				(type default)
			)
			(fill no)
			(layer "B.CrtYd")
		)
		(fp_rect
			(start 0.9652 1.778)
			(end -0.9652 -1.778)
			(stroke
				(width 0)
				(type default)
			)
			(fill no)
			(layer "B.Fab")
		)
		(pad "1" smd rect
			(at 0 -0.9652 90)
			(size 1.397 1.143)
			(layers "B.Cu" "B.Mask" "B.Paste")
			(net "P0V9_LX")
		)
		(pad "2" smd rect
			(at 0 0.9652 90)
			(size 1.397 1.143)
			(layers "B.Cu" "B.Mask" "B.Paste")
			(net "P0V9_SNB")
		)
	)
	(footprint ""
		(layer "B.Cu")
		(at 22.5298 -133.3246)
		(property "Reference" "TP96"
			(at 0 0 0)
			(layer "B.SilkS")
			(hide yes)
			(effects
				(font
					(size 1.27 1.27)
				)
				(justify mirror)
			)
		)
		(property "Value" "TPAD28-2-GP"
			(at 0.0127 -1.6637 0)
			(unlocked yes)
			(layer "B.Fab")
			(hide yes)
			(effects
				(font
					(size 1.016 1.016)
					(thickness 0.1524)
				)
				(justify mirror)
			)
		)
		(property "Device Type" "TPAD28"
			(at 0.0127 -3.1877 0)
			(unlocked yes)
			(layer "B.Fab")
			(hide yes)
			(effects
				(font
					(size 1.016 1.016)
					(thickness 0.1524)
				)
				(justify mirror)
			)
		)
		(duplicate_pad_numbers_are_jumpers no)
		(fp_poly
			(pts
				(arc
					(start 0.3556 0)
					(mid -0.3556 0)
					(end 0.3556 0)
				)
			)
			(stroke
				(width 0)
				(type default)
			)
			(fill no)
			(layer "B.CrtYd")
		)
		(fp_poly
			(pts
				(arc
					(start 0.6096 0)
					(mid -0.6096 0)
					(end 0.6096 0)
				)
			)
			(stroke
				(width 0)
				(type default)
			)
			(fill no)
			(layer "B.Fab")
		)
		(pad "1" smd circle
			(at 0 0 180)
			(size 0.7112 0.7112)
			(layers "B.Cu" "B.Mask" "B.Paste")
			(net "TP_GPIOS4")
		)
	)
	(footprint ""
		(layer "B.Cu")
		(at 45.085 -116.713)
		(property "Reference" "R537"
			(at 0 0 0)
			(layer "B.SilkS")
			(hide yes)
			(effects
				(font
					(size 1.27 1.27)
				)
				(justify mirror)
			)
		)
		(property "Value" "0R2J-2-GP"
			(at -0.064008 -3.993896 0)
			(unlocked yes)
			(layer "B.Fab")
			(hide yes)
			(effects
				(font
					(size 1.016 1.016)
					(thickness 0.1524)
				)
				(justify mirror)
			)
		)
		(property "Device Type" "R402H16"
			(at -0.064008 -5.517896 0)
			(unlocked yes)
			(layer "B.Fab")
			(hide yes)
			(effects
				(font
					(size 1.016 1.016)
					(thickness 0.1524)
				)
				(justify mirror)
			)
		)
		(duplicate_pad_numbers_are_jumpers no)
		(fp_line
			(start -0.508 -0.9398)
			(end 0.508 -0.9398)
			(stroke
				(width 0.1524)
				(type default)
			)
			(layer "B.SilkS")
		)
		(fp_line
			(start 0.508 -0.9398)
			(end 0.508 0.9398)
			(stroke
				(width 0.1524)
				(type default)
			)
			(layer "B.SilkS")
		)
		(fp_rect
			(start 0.508 0.9398)
			(end -0.508 -0.9398)
			(stroke
				(width 0)
				(type default)
			)
			(fill no)
			(layer "B.CrtYd")
		)
		(fp_rect
			(start 0.508 0.9398)
			(end -0.508 -0.9398)
			(stroke
				(width 0)
				(type default)
			)
			(fill no)
			(layer "B.Fab")
		)
		(pad "1" smd custom
			(at 0 -0.4445 180)
			(size 0.1397 0.1397)
			(layers "B.Cu" "B.Mask" "B.Paste")
			(net "PEER_TRAY_BMC")
			(options
				(clearance outline)
				(anchor circle)
			)
			(primitives
				(gr_poly
					(pts
						(arc
							(start -0.1778 0.2794)
							(mid -0.249642 0.249642)
							(end -0.2794 0.1778)
						)
						(arc
							(start -0.2794 -0.1778)
							(mid -0.249642 -0.249642)
							(end -0.1778 -0.2794)
						)
						(arc
							(start 0.1778 -0.2794)
							(mid 0.249642 -0.249642)
							(end 0.2794 -0.1778)
						)
						(arc
							(start 0.2794 0.1778)
							(mid 0.249642 0.249642)
							(end 0.1778 0.2794)
						)
					)
					(width 0)
					(fill yes)
				)
			)
		)
		(pad "2" smd custom
			(at 0 0.4445 180)
			(size 0.1397 0.1397)
			(layers "B.Cu" "B.Mask" "B.Paste")
			(net "PEER_TRAY_R")
			(options
				(clearance outline)
				(anchor circle)
			)
			(primitives
				(gr_poly
					(pts
						(arc
							(start -0.1778 0.2794)
							(mid -0.249642 0.249642)
							(end -0.2794 0.1778)
						)
						(arc
							(start -0.2794 -0.1778)
							(mid -0.249642 -0.249642)
							(end -0.1778 -0.2794)
						)
						(arc
							(start 0.1778 -0.2794)
							(mid 0.249642 -0.249642)
							(end 0.2794 -0.1778)
						)
						(arc
							(start 0.2794 0.1778)
							(mid 0.249642 0.249642)
							(end 0.1778 0.2794)
						)
					)
					(width 0)
					(fill yes)
				)
			)
		)
	)
	(footprint ""
		(layer "B.Cu")
		(at 69.469 -186.5376)
		(property "Reference" "C3213"
			(at 0 0 0)
			(layer "B.SilkS")
			(hide yes)
			(effects
				(font
					(size 1.27 1.27)
				)
				(justify mirror)
			)
		)
		(property "Value" "SCD1U25V2KX-2-GP"
			(at -1.1811 -2.7051 0)
			(unlocked yes)
			(layer "B.Fab")
			(hide yes)
			(effects
				(font
					(size 1.016 1.016)
					(thickness 0.1524)
				)
				(justify mirror)
			)
		)
		(property "Device Type" "C402H22"
			(at -1.1811 -4.2291 0)
			(unlocked yes)
			(layer "B.Fab")
			(hide yes)
			(effects
				(font
					(size 1.016 1.016)
					(thickness 0.1524)
				)
				(justify mirror)
			)
		)
		(duplicate_pad_numbers_are_jumpers no)
		(fp_rect
			(start 0.4318 0.9525)
			(end -0.4318 -0.9525)
			(stroke
				(width 0)
				(type default)
			)
			(fill no)
			(layer "B.CrtYd")
		)
		(fp_rect
			(start 0.4318 0.9525)
			(end -0.4318 -0.9525)
			(stroke
				(width 0)
				(type default)
			)
			(fill no)
			(layer "B.Fab")
		)
		(pad "1" smd custom
			(at 0 -0.4445 180)
			(size 0.1524 0.1524)
			(layers "B.Cu" "B.Mask" "B.Paste")
			(net "P3V3_STBY")
			(options
				(clearance outline)
				(anchor circle)
			)
			(primitives
				(gr_poly
					(pts
						(arc
							(start 0.3048 0.2032)
							(mid 0.275042 0.275042)
							(end 0.2032 0.3048)
						)
						(arc
							(start -0.2032 0.3048)
							(mid -0.275042 0.275042)
							(end -0.3048 0.2032)
						)
						(arc
							(start -0.3048 -0.2032)
							(mid -0.275042 -0.275042)
							(end -0.2032 -0.3048)
						)
						(arc
							(start 0.2032 -0.3048)
							(mid 0.275042 -0.275042)
							(end 0.3048 -0.2032)
						)
					)
					(width 0)
					(fill yes)
				)
			)
		)
		(pad "2" smd custom
			(at 0 0.4445 180)
			(size 0.1524 0.1524)
			(layers "B.Cu" "B.Mask" "B.Paste")
			(net "GND")
			(options
				(clearance outline)
				(anchor circle)
			)
			(primitives
				(gr_poly
					(pts
						(arc
							(start 0.3048 0.2032)
							(mid 0.275042 0.275042)
							(end 0.2032 0.3048)
						)
						(arc
							(start -0.2032 0.3048)
							(mid -0.275042 0.275042)
							(end -0.3048 0.2032)
						)
						(arc
							(start -0.3048 -0.2032)
							(mid -0.275042 -0.275042)
							(end -0.2032 -0.3048)
						)
						(arc
							(start 0.2032 -0.3048)
							(mid 0.275042 -0.275042)
							(end 0.3048 -0.2032)
						)
					)
					(width 0)
					(fill yes)
				)
			)
		)
	)
	(footprint ""
		(layer "B.Cu")
		(at 162.306 -88.4174 180)
		(property "Reference" "C713"
			(at 0 0 0)
			(layer "B.SilkS")
			(hide yes)
			(effects
				(font
					(size 1.27 1.27)
				)
				(justify mirror)
			)
		)
		(property "Value" "SCD1U10V2KX-5GP"
			(at -1.1811 -2.7051 180)
			(unlocked yes)
			(layer "B.Fab")
			(hide yes)
			(effects
				(font
					(size 1.016 1.016)
					(thickness 0.1524)
				)
				(justify mirror)
			)
		)
		(property "Device Type" "C402H22"
			(at -1.1811 -4.2291 180)
			(unlocked yes)
			(layer "B.Fab")
			(hide yes)
			(effects
				(font
					(size 1.016 1.016)
					(thickness 0.1524)
				)
				(justify mirror)
			)
		)
		(duplicate_pad_numbers_are_jumpers no)
		(fp_rect
			(start 0.4318 0.9525)
			(end -0.4318 -0.9525)
			(stroke
				(width 0)
				(type default)
			)
			(fill no)
			(layer "B.CrtYd")
		)
		(fp_rect
			(start 0.4318 0.9525)
			(end -0.4318 -0.9525)
			(stroke
				(width 0)
				(type default)
			)
			(fill no)
			(layer "B.Fab")
		)
		(pad "1" smd custom
			(at 0 -0.4445)
			(size 0.1524 0.1524)
			(layers "B.Cu" "B.Mask" "B.Paste")
			(net "P1V8_CLKGEN")
			(options
				(clearance outline)
				(anchor circle)
			)
			(primitives
				(gr_poly
					(pts
						(arc
							(start 0.3048 0.2032)
							(mid 0.275042 0.275042)
							(end 0.2032 0.3048)
						)
						(arc
							(start -0.2032 0.3048)
							(mid -0.275042 0.275042)
							(end -0.3048 0.2032)
						)
						(arc
							(start -0.3048 -0.2032)
							(mid -0.275042 -0.275042)
							(end -0.2032 -0.3048)
						)
						(arc
							(start 0.2032 -0.3048)
							(mid 0.275042 -0.275042)
							(end 0.3048 -0.2032)
						)
					)
					(width 0)
					(fill yes)
				)
			)
		)
		(pad "2" smd custom
			(at 0 0.4445)
			(size 0.1524 0.1524)
			(layers "B.Cu" "B.Mask" "B.Paste")
			(net "GND")
			(options
				(clearance outline)
				(anchor circle)
			)
			(primitives
				(gr_poly
					(pts
						(arc
							(start 0.3048 0.2032)
							(mid 0.275042 0.275042)
							(end 0.2032 0.3048)
						)
						(arc
							(start -0.2032 0.3048)
							(mid -0.275042 0.275042)
							(end -0.3048 0.2032)
						)
						(arc
							(start -0.3048 -0.2032)
							(mid -0.275042 -0.275042)
							(end -0.2032 -0.3048)
						)
						(arc
							(start 0.2032 -0.3048)
							(mid 0.275042 -0.275042)
							(end 0.3048 -0.2032)
						)
					)
					(width 0)
					(fill yes)
				)
			)
		)
	)
	(footprint ""
		(layer "B.Cu")
		(at 241.2746 -37.9984 -90)
		(property "Reference" "C468"
			(at 0 0 90)
			(layer "B.SilkS")
			(hide yes)
			(effects
				(font
					(size 1.27 1.27)
				)
				(justify mirror)
			)
		)
		(property "Value" "SCD1U16V1KX-1-GP"
			(at 2.8321 -1.7399 270)
			(unlocked yes)
			(layer "B.Fab")
			(hide yes)
			(effects
				(font
					(size 1.016 1.016)
					(thickness 0.1524)
				)
				(justify mirror)
			)
		)
		(property "Device Type" "C0201H13"
			(at 2.8321 -3.2639 270)
			(unlocked yes)
			(layer "B.Fab")
			(hide yes)
			(effects
				(font
					(size 1.016 1.016)
					(thickness 0.1524)
				)
				(justify mirror)
			)
		)
		(duplicate_pad_numbers_are_jumpers no)
		(fp_rect
			(start 0.2794 0.6477)
			(end -0.2794 -0.6477)
			(stroke
				(width 0)
				(type default)
			)
			(fill no)
			(layer "B.CrtYd")
		)
		(fp_rect
			(start 0.2794 0.6477)
			(end -0.2794 -0.6477)
			(stroke
				(width 0)
				(type default)
			)
			(fill no)
			(layer "B.Fab")
		)
		(pad "1" smd custom
			(at 0 -0.2794 90)
			(size 0.0762 0.0762)
			(layers "B.Cu" "B.Mask" "B.Paste")
			(net "DUT_VDDO_REF")
			(options
				(clearance outline)
				(anchor circle)
			)
			(primitives
				(gr_poly
					(pts
						(arc
							(start 0.1524 0.127)
							(mid 0.137521 0.162921)
							(end 0.1016 0.1778)
						)
						(arc
							(start -0.1016 0.1778)
							(mid -0.137521 0.162921)
							(end -0.1524 0.127)
						)
						(arc
							(start -0.1524 -0.127)
							(mid -0.137521 -0.162921)
							(end -0.1016 -0.1778)
						)
						(arc
							(start 0.1016 -0.1778)
							(mid 0.137521 -0.162921)
							(end 0.1524 -0.127)
						)
					)
					(width 0)
					(fill yes)
				)
			)
		)
		(pad "2" smd custom
			(at 0 0.2794 90)
			(size 0.0762 0.0762)
			(layers "B.Cu" "B.Mask" "B.Paste")
			(net "GND")
			(options
				(clearance outline)
				(anchor circle)
			)
			(primitives
				(gr_poly
					(pts
						(arc
							(start 0.1524 0.127)
							(mid 0.137521 0.162921)
							(end 0.1016 0.1778)
						)
						(arc
							(start -0.1016 0.1778)
							(mid -0.137521 0.162921)
							(end -0.1524 0.127)
						)
						(arc
							(start -0.1524 -0.127)
							(mid -0.137521 -0.162921)
							(end -0.1016 -0.1778)
						)
						(arc
							(start 0.1016 -0.1778)
							(mid 0.137521 -0.162921)
							(end 0.1524 -0.127)
						)
					)
					(width 0)
					(fill yes)
				)
			)
		)
	)
	(footprint ""
		(layer "B.Cu")
		(at 224.536 -23.241 180)
		(property "Reference" "R830"
			(at 0 0 0)
			(layer "B.SilkS")
			(hide yes)
			(effects
				(font
					(size 1.27 1.27)
				)
				(justify mirror)
			)
		)
		(property "Value" "0R2J-2-GP"
			(at -0.064008 -3.993896 180)
			(unlocked yes)
			(layer "B.Fab")
			(hide yes)
			(effects
				(font
					(size 1.016 1.016)
					(thickness 0.1524)
				)
				(justify mirror)
			)
		)
		(property "Device Type" "R402H16"
			(at -0.064008 -5.517896 180)
			(unlocked yes)
			(layer "B.Fab")
			(hide yes)
			(effects
				(font
					(size 1.016 1.016)
					(thickness 0.1524)
				)
				(justify mirror)
			)
		)
		(duplicate_pad_numbers_are_jumpers no)
		(fp_line
			(start 0.508 -0.9398)
			(end 0.508 0.9398)
			(stroke
				(width 0.1524)
				(type default)
			)
			(layer "B.SilkS")
		)
		(fp_line
			(start -0.508 -0.9398)
			(end 0.508 -0.9398)
			(stroke
				(width 0.1524)
				(type default)
			)
			(layer "B.SilkS")
		)
		(fp_rect
			(start 0.508 0.9398)
			(end -0.508 -0.9398)
			(stroke
				(width 0)
				(type default)
			)
			(fill no)
			(layer "B.CrtYd")
		)
		(fp_rect
			(start 0.508 0.9398)
			(end -0.508 -0.9398)
			(stroke
				(width 0)
				(type default)
			)
			(fill no)
			(layer "B.Fab")
		)
		(pad "1" smd custom
			(at 0 -0.4445)
			(size 0.1397 0.1397)
			(layers "B.Cu" "B.Mask" "B.Paste")
			(net "HOST6_RST_N_LS")
			(options
				(clearance outline)
				(anchor circle)
			)
			(primitives
				(gr_poly
					(pts
						(arc
							(start -0.1778 0.2794)
							(mid -0.249642 0.249642)
							(end -0.2794 0.1778)
						)
						(arc
							(start -0.2794 -0.1778)
							(mid -0.249642 -0.249642)
							(end -0.1778 -0.2794)
						)
						(arc
							(start 0.1778 -0.2794)
							(mid 0.249642 -0.249642)
							(end 0.2794 -0.1778)
						)
						(arc
							(start 0.2794 0.1778)
							(mid 0.249642 0.249642)
							(end 0.1778 0.2794)
						)
					)
					(width 0)
					(fill yes)
				)
			)
		)
		(pad "2" smd custom
			(at 0 0.4445)
			(size 0.1397 0.1397)
			(layers "B.Cu" "B.Mask" "B.Paste")
			(net "LBI_ADDR_5_R")
			(options
				(clearance outline)
				(anchor circle)
			)
			(primitives
				(gr_poly
					(pts
						(arc
							(start -0.1778 0.2794)
							(mid -0.249642 0.249642)
							(end -0.2794 0.1778)
						)
						(arc
							(start -0.2794 -0.1778)
							(mid -0.249642 -0.249642)
							(end -0.1778 -0.2794)
						)
						(arc
							(start 0.1778 -0.2794)
							(mid 0.249642 -0.249642)
							(end 0.2794 -0.1778)
						)
						(arc
							(start 0.2794 0.1778)
							(mid 0.249642 0.249642)
							(end 0.1778 0.2794)
						)
					)
					(width 0)
					(fill yes)
				)
			)
		)
	)
	(footprint ""
		(layer "B.Cu")
		(at 228.6254 -42.994072 90)
		(property "Reference" "C574"
			(at 0 0 90)
			(layer "B.SilkS")
			(hide yes)
			(effects
				(font
					(size 1.27 1.27)
				)
				(justify mirror)
			)
		)
		(property "Value" "SCD1U16V1KX-1-GP"
			(at 2.8321 -1.7399 90)
			(unlocked yes)
			(layer "B.Fab")
			(hide yes)
			(effects
				(font
					(size 1.016 1.016)
					(thickness 0.1524)
				)
				(justify mirror)
			)
		)
		(property "Device Type" "C0201H13"
			(at 2.8321 -3.2639 90)
			(unlocked yes)
			(layer "B.Fab")
			(hide yes)
			(effects
				(font
					(size 1.016 1.016)
					(thickness 0.1524)
				)
				(justify mirror)
			)
		)
		(duplicate_pad_numbers_are_jumpers no)
		(fp_rect
			(start 0.2794 0.6477)
			(end -0.2794 -0.6477)
			(stroke
				(width 0)
				(type default)
			)
			(fill no)
			(layer "B.CrtYd")
		)
		(fp_rect
			(start 0.2794 0.6477)
			(end -0.2794 -0.6477)
			(stroke
				(width 0)
				(type default)
			)
			(fill no)
			(layer "B.Fab")
		)
		(pad "1" smd custom
			(at 0 -0.2794 270)
			(size 0.0762 0.0762)
			(layers "B.Cu" "B.Mask" "B.Paste")
			(net "DUT_AVD_PCIE")
			(options
				(clearance outline)
				(anchor circle)
			)
			(primitives
				(gr_poly
					(pts
						(arc
							(start 0.1524 0.127)
							(mid 0.137521 0.162921)
							(end 0.1016 0.1778)
						)
						(arc
							(start -0.1016 0.1778)
							(mid -0.137521 0.162921)
							(end -0.1524 0.127)
						)
						(arc
							(start -0.1524 -0.127)
							(mid -0.137521 -0.162921)
							(end -0.1016 -0.1778)
						)
						(arc
							(start 0.1016 -0.1778)
							(mid 0.137521 -0.162921)
							(end 0.1524 -0.127)
						)
					)
					(width 0)
					(fill yes)
				)
			)
		)
		(pad "2" smd custom
			(at 0 0.2794 270)
			(size 0.0762 0.0762)
			(layers "B.Cu" "B.Mask" "B.Paste")
			(net "GND")
			(options
				(clearance outline)
				(anchor circle)
			)
			(primitives
				(gr_poly
					(pts
						(arc
							(start 0.1524 0.127)
							(mid 0.137521 0.162921)
							(end 0.1016 0.1778)
						)
						(arc
							(start -0.1016 0.1778)
							(mid -0.137521 0.162921)
							(end -0.1524 0.127)
						)
						(arc
							(start -0.1524 -0.127)
							(mid -0.137521 -0.162921)
							(end -0.1016 -0.1778)
						)
						(arc
							(start 0.1016 -0.1778)
							(mid 0.137521 -0.162921)
							(end 0.1524 -0.127)
						)
					)
					(width 0)
					(fill yes)
				)
			)
		)
	)
)
